(kicad_pcb
	(version 20241229)
	(generator "pcbnew")
	(generator_version "9.0")
	(general
		(thickness 1.711)
		(legacy_teardrops no)
	)
	(paper "A4")
	(title_block
		(title "Antmicro Baseboard for Jetson AGX Thor")
		(date "2026-02-18")
		(rev "1.1.0")
		(company "Antmicro Ltd")
		(comment 1 "www.antmicro.com")
		(comment 9 "footprints 952-955 of 1170")
	)
	(layers
		(0 "F.Cu" signal)
		(4 "In1.Cu" signal)
		(6 "In2.Cu" signal)
		(8 "In3.Cu" signal)
		(10 "In4.Cu" jumper)
		(12 "In5.Cu" signal)
		(14 "In6.Cu" signal)
		(16 "In7.Cu" signal)
		(18 "In8.Cu" signal)
		(2 "B.Cu" signal)
		(9 "F.Adhes" user "F.Adhesive")
		(11 "B.Adhes" user "B.Adhesive")
		(13 "F.Paste" user)
		(15 "B.Paste" user)
		(5 "F.SilkS" user "F.Silkscreen")
		(7 "B.SilkS" user "B.Silkscreen")
		(1 "F.Mask" user)
		(3 "B.Mask" user)
		(17 "Dwgs.User" user "User.Drawings")
		(19 "Cmts.User" user "User.Comments")
		(21 "Eco1.User" user "User.Eco1")
		(23 "Eco2.User" user "User.Eco2")
		(25 "Edge.Cuts" user)
		(27 "Margin" user)
		(31 "F.CrtYd" user "F.Courtyard")
		(29 "B.CrtYd" user "B.Courtyard")
		(35 "F.Fab" user)
		(33 "B.Fab" user)
	)
	(footprint "antmicro-footprints:Vishay_PowerPAK_1212-8_Single"
		(layer "B.Cu")
		(at 183.08 75.564 90)
		(descr "PowerPAK 1212-8 Single")
		(tags "Vishay PowerPAK 1212-8 Single")
		(property "Reference" "Q25"
			(at -0.036 1.92 90)
			(layer "B.SilkS")
			(effects
				(font
					(size 0.7 0.7)
					(thickness 0.15)
				)
				(justify right top mirror)
			)
		)
		(property "Value" "SISS05DN-T1-GE3"
			(at 0 -2.7 90)
			(layer "B.Fab")
			(effects
				(font
					(size 0.7 0.7)
					(thickness 0.15)
				)
				(justify right top mirror)
			)
		)
		(property "Datasheet" "https://www.vishay.com/docs/77029/siss05dn.pdf"
			(at 0 0 90)
			(layer "B.Fab")
			(hide yes)
			(effects
				(font
					(size 1.27 1.27)
					(thickness 0.15)
				)
				(justify mirror)
			)
		)
		(property "Description" "Power MOSFET, P Channel, 30 V, 108 A, 0.0035 ohm, PowerPAK 1212, Surface Mount"
			(at 0 0 90)
			(layer "B.Fab")
			(hide yes)
			(effects
				(font
					(size 1.27 1.27)
					(thickness 0.15)
				)
				(justify mirror)
			)
		)
		(property "MPN" "SISS05DN-T1-GE3"
			(at 0 0 270)
			(unlocked yes)
			(layer "B.Fab")
			(hide yes)
			(effects
				(font
					(size 1 1)
					(thickness 0.15)
				)
				(justify mirror)
			)
		)
		(property "Manufacturer" "Vishay"
			(at 0 0 270)
			(unlocked yes)
			(layer "B.Fab")
			(hide yes)
			(effects
				(font
					(size 1 1)
					(thickness 0.15)
				)
				(justify mirror)
			)
		)
		(property "Author" "Antmicro"
			(at 0 0 270)
			(unlocked yes)
			(layer "B.Fab")
			(hide yes)
			(effects
				(font
					(size 1 1)
					(thickness 0.15)
				)
				(justify mirror)
			)
		)
		(property "License" "Apache-2.0"
			(at 0 0 270)
			(unlocked yes)
			(layer "B.Fab")
			(hide yes)
			(effects
				(font
					(size 1 1)
					(thickness 0.15)
				)
				(justify mirror)
			)
		)
		(sheetname "/Power/")
		(sheetfile "power.kicad_sch")
		(attr smd)
		(fp_line
			(start -1.635 -1.634)
			(end 1.634 -1.634)
			(stroke
				(width 0.15)
				(type solid)
			)
			(layer "B.SilkS")
		)
		(fp_line
			(start 1.634 -1.3)
			(end 1.634 -1.634)
			(stroke
				(width 0.15)
				(type solid)
			)
			(layer "B.SilkS")
		)
		(fp_line
			(start -1.635 -1.3)
			(end -1.635 -1.634)
			(stroke
				(width 0.15)
				(type solid)
			)
			(layer "B.SilkS")
		)
		(fp_line
			(start 1.648 1.651)
			(end 1.648 1.317)
			(stroke
				(width 0.15)
				(type solid)
			)
			(layer "B.SilkS")
		)
		(fp_line
			(start -1.651 1.651)
			(end -1.651 1.317)
			(stroke
				(width 0.15)
				(type solid)
			)
			(layer "B.SilkS")
		)
		(fp_line
			(start -1.651 1.651)
			(end 1.648 1.651)
			(stroke
				(width 0.15)
				(type solid)
			)
			(layer "B.SilkS")
		)
		(fp_circle
			(center -1.9 1.4)
			(end -1.85 1.4)
			(stroke
				(width 0.15)
				(type solid)
			)
			(fill yes)
			(layer "B.SilkS")
		)
		(fp_rect
			(start -2 1.8)
			(end 2 -1.798)
			(stroke
				(width 0.05)
				(type solid)
			)
			(fill no)
			(layer "B.CrtYd")
		)
		(fp_line
			(start -1.6425 1.4175)
			(end -1.4175 1.6425)
			(stroke
				(width 0.15)
				(type solid)
			)
			(layer "B.Fab")
		)
		(fp_rect
			(start -1.651 1.651)
			(end 1.648 -1.648)
			(stroke
				(width 0.15)
				(type solid)
			)
			(fill no)
			(layer "B.Fab")
		)
		(fp_text user "License: Apache-2.0"
			(at -8 -7.1 90)
			(layer "B.Fab")
			(effects
				(font
					(size 0.7 0.7)
					(thickness 0.15)
				)
				(justify right top mirror)
			)
		)
		(fp_text user "Author: Antmicro"
			(at -8 -5.9 90)
			(layer "B.Fab")
			(effects
				(font
					(size 0.7 0.7)
					(thickness 0.15)
				)
				(justify right top mirror)
			)
		)
		(fp_text user "${REFERENCE}"
			(at -8 -4.7 90)
			(layer "B.Fab")
			(effects
				(font
					(size 0.7 0.7)
					(thickness 0.15)
				)
				(justify right top mirror)
			)
		)
		(pad "1" smd rect
			(at -1.436 0.99 90)
			(size 0.99 0.405)
			(layers "B.Cu" "B.Mask" "B.Paste")
			(net 525 "/Power/USBPD2_HV")
			(pinfunction "S")
			(pintype "passive")
		)
		(pad "2" smd rect
			(at -1.436 0.332 90)
			(size 0.99 0.405)
			(layers "B.Cu" "B.Mask" "B.Paste")
			(net 525 "/Power/USBPD2_HV")
			(pinfunction "S")
			(pintype "passive")
		)
		(pad "3" smd rect
			(at -1.436 -0.33 90)
			(size 0.99 0.405)
			(layers "B.Cu" "B.Mask" "B.Paste")
			(net 525 "/Power/USBPD2_HV")
			(pinfunction "S")
			(pintype "passive")
		)
		(pad "4" smd rect
			(at -1.436 -0.988 90)
			(size 0.99 0.405)
			(layers "B.Cu" "B.Mask" "B.Paste")
			(net 1203 "Net-(Q25-G)")
			(pinfunction "G")
			(pintype "input")
		)
		(pad "5" smd custom
			(at 0.557 0 90)
			(size 1.725 2.235)
			(layers "B.Cu" "B.Mask" "B.Paste")
			(net 904 "+20V")
			(pinfunction "D")
			(pintype "passive")
			(zone_connect 2)
			(options
				(clearance outline)
				(anchor rect)
			)
			(primitives
				(gr_poly
					(pts
						(xy 0.8625 -0.1275) (xy 0.8625 0.1275) (xy 1.3725 0.1275) (xy 1.3725 0.5325) (xy 0.8625 0.5325)
						(xy 0.8625 0.7875) (xy 1.3725 0.7875) (xy 1.3725 1.195) (xy 0.6125 1.195) (xy 0.6125 -1.195) (xy 1.3725 -1.195)
						(xy 1.3725 -0.7875) (xy 0.8625 -0.7875) (xy 0.8625 -0.5325) (xy 1.3725 -0.5325) (xy 1.3725 -0.1275)
					)
					(width 0)
					(fill yes)
				)
			)
		)
	)
	(footprint "antmicro-footprints:R_0402_1005Metric"
		(layer "B.Cu")
		(at 238.1 80.45 180)
		(descr "Resistor SMD 0402")
		(tags "resistor SMD 0402")
		(property "Reference" "R149"
			(at -1.5 2.65 0)
			(layer "B.SilkS")
			(effects
				(font
					(size 0.7 0.7)
					(thickness 0.15)
				)
				(justify left bottom mirror)
			)
		)
		(property "Value" "R_0R_0402"
			(at -1.011843 -1.772046 0)
			(layer "B.Fab")
			(effects
				(font
					(size 0.7 0.7)
					(thickness 0.15)
				)
				(justify left bottom mirror)
			)
		)
		(property "Datasheet" "https://industrial.panasonic.com/cdbs/www-data/pdf/RDA0000/AOA0000C301.pdf"
			(at 0 0 0)
			(layer "B.Fab")
			(hide yes)
			(effects
				(font
					(size 1.27 1.27)
					(thickness 0.15)
				)
				(justify mirror)
			)
		)
		(property "Description" "SMD Chip Resistor, Jumper, 0 ohm, 100 mW, 0402 [1005 Metric], Thick Film, General Purpose"
			(at 0 0 0)
			(layer "B.Fab")
			(hide yes)
			(effects
				(font
					(size 1.27 1.27)
					(thickness 0.15)
				)
				(justify mirror)
			)
		)
		(property "Manufacturer" "Panasonic"
			(at 0 0 0)
			(unlocked yes)
			(layer "B.Fab")
			(hide yes)
			(effects
				(font
					(size 1 1)
					(thickness 0.15)
				)
				(justify mirror)
			)
		)
		(property "MPN" "ERJ2GE0R00X"
			(at 0 0 0)
			(unlocked yes)
			(layer "B.Fab")
			(hide yes)
			(effects
				(font
					(size 1 1)
					(thickness 0.15)
				)
				(justify mirror)
			)
		)
		(property "Val" "0R"
			(at 0 0 0)
			(unlocked yes)
			(layer "B.Fab")
			(hide yes)
			(effects
				(font
					(size 1 1)
					(thickness 0.15)
				)
				(justify mirror)
			)
		)
		(property "License" "Apache-2.0"
			(at 0 0 0)
			(unlocked yes)
			(layer "B.Fab")
			(hide yes)
			(effects
				(font
					(size 1 1)
					(thickness 0.15)
				)
				(justify mirror)
			)
		)
		(property "Author" "Antmicro"
			(at 0 0 0)
			(unlocked yes)
			(layer "B.Fab")
			(hide yes)
			(effects
				(font
					(size 1 1)
					(thickness 0.15)
				)
				(justify mirror)
			)
		)
		(property "Tolerance" "~"
			(at 0 0 0)
			(unlocked yes)
			(layer "B.Fab")
			(hide yes)
			(effects
				(font
					(size 1 1)
					(thickness 0.15)
				)
				(justify mirror)
			)
		)
		(property "Current" "1A"
			(at 0 0 0)
			(unlocked yes)
			(layer "B.Fab")
			(hide yes)
			(effects
				(font
					(size 1 1)
					(thickness 0.15)
				)
				(justify mirror)
			)
		)
		(sheetname "/USB Debug, PD/")
		(sheetfile "usb_debug_pd.kicad_sch")
		(attr smd exclude_from_pos_files exclude_from_bom dnp)
		(fp_poly
			(pts
				(xy -0.925 0.47) (xy -0.925 -0.47) (xy 0.925 -0.47) (xy 0.925 0.47)
			)
			(stroke
				(width 0.05)
				(type default)
			)
			(fill no)
			(layer "B.CrtYd")
		)
		(fp_poly
			(pts
				(xy -0.5 0.25) (xy -0.5 -0.25) (xy 0.5 -0.25) (xy 0.5 0.25)
			)
			(stroke
				(width 0.15)
				(type solid)
			)
			(fill no)
			(layer "B.Fab")
		)
		(fp_text user "${REFERENCE}"
			(at -0.95 -3.168 0)
			(layer "B.Fab")
			(effects
				(font
					(size 0.7 0.7)
					(thickness 0.15)
				)
				(justify left bottom mirror)
			)
		)
		(fp_text user "Author: Antmicro"
			(at -0.95 -4.169 0)
			(layer "B.Fab")
			(effects
				(font
					(size 0.7 0.7)
					(thickness 0.15)
				)
				(justify left bottom mirror)
			)
		)
		(fp_text user "License: Apache-2.0"
			(at -0.949999 -5.169 0)
			(layer "B.Fab")
			(effects
				(font
					(size 0.7 0.7)
					(thickness 0.15)
				)
				(justify left bottom mirror)
			)
		)
		(pad "1" smd roundrect
			(at -0.48 0 180)
			(size 0.59 0.64)
			(layers "B.Cu" "B.Mask" "B.Paste")
			(roundrect_rratio 0.25)
			(net 975 "/USB Debug, PD/USBC0_5V_PEN")
			(pintype "passive")
		)
		(pad "2" smd roundrect
			(at 0.48 0 180)
			(size 0.59 0.64)
			(layers "B.Cu" "B.Mask" "B.Paste")
			(roundrect_rratio 0.25)
			(net 5 "+5V")
			(pintype "passive")
		)
	)
	(footprint "antmicro-footprints:C_0402_1005Metric"
		(layer "B.Cu")
		(at 230.07 126.9 180)
		(descr "Capacitor SMD 0402")
		(tags "capacitor SMD 0402")
		(property "Reference" "C106"
			(at -2.13 -1.4 0)
			(layer "B.SilkS")
			(effects
				(font
					(size 0.7 0.7)
					(thickness 0.15)
				)
				(justify left bottom mirror)
			)
		)
		(property "Value" "C_100n_0402"
			(at -1.022927 -2.155213 0)
			(layer "B.Fab")
			(effects
				(font
					(size 0.7 0.7)
					(thickness 0.15)
				)
				(justify left bottom mirror)
			)
		)
		(property "Datasheet" "https://www.murata.com/products/productdetail?partno=GRM155R61H104KE14%23"
			(at 0 0 0)
			(layer "B.Fab")
			(hide yes)
			(effects
				(font
					(size 1.27 1.27)
					(thickness 0.15)
				)
				(justify mirror)
			)
		)
		(property "Description" "SMD Multilayer Ceramic Capacitor, 0.1 µF, 50 V, 0402 [1005 Metric], ± 10%, X5R, GRM Series"
			(at 0 0 0)
			(layer "B.Fab")
			(hide yes)
			(effects
				(font
					(size 1.27 1.27)
					(thickness 0.15)
				)
				(justify mirror)
			)
		)
		(property "Manufacturer" "Murata"
			(at 0 0 0)
			(unlocked yes)
			(layer "B.Fab")
			(hide yes)
			(effects
				(font
					(size 1 1)
					(thickness 0.15)
				)
				(justify mirror)
			)
		)
		(property "MPN" "GRM155R61H104KE14D"
			(at 0 0 0)
			(unlocked yes)
			(layer "B.Fab")
			(hide yes)
			(effects
				(font
					(size 1 1)
					(thickness 0.15)
				)
				(justify mirror)
			)
		)
		(property "Val" "100n"
			(at 0 0 0)
			(unlocked yes)
			(layer "B.Fab")
			(hide yes)
			(effects
				(font
					(size 1 1)
					(thickness 0.15)
				)
				(justify mirror)
			)
		)
		(property "License" "Apache-2.0"
			(at 0 0 0)
			(unlocked yes)
			(layer "B.Fab")
			(hide yes)
			(effects
				(font
					(size 1 1)
					(thickness 0.15)
				)
				(justify mirror)
			)
		)
		(property "Author" "Antmicro"
			(at 0 0 0)
			(unlocked yes)
			(layer "B.Fab")
			(hide yes)
			(effects
				(font
					(size 1 1)
					(thickness 0.15)
				)
				(justify mirror)
			)
		)
		(property "Voltage" "50V"
			(at 0 0 0)
			(unlocked yes)
			(layer "B.Fab")
			(hide yes)
			(effects
				(font
					(size 1 1)
					(thickness 0.15)
				)
				(justify mirror)
			)
		)
		(property "Dielectric" "X5R"
			(at 0 0 0)
			(unlocked yes)
			(layer "B.Fab")
			(hide yes)
			(effects
				(font
					(size 1 1)
					(thickness 0.15)
				)
				(justify mirror)
			)
		)
		(sheetname "/USB Hub/")
		(sheetfile "usb_hub.kicad_sch")
		(attr smd)
		(fp_poly
			(pts
				(xy -0.925 0.47) (xy 0.925 0.47) (xy 0.925 -0.47) (xy -0.925 -0.47)
			)
			(stroke
				(width 0.05)
				(type default)
			)
			(fill no)
			(layer "B.CrtYd")
		)
		(fp_line
			(start 0.504 0.25)
			(end 0.504 -0.248)
			(stroke
				(width 0.15)
				(type solid)
			)
			(layer "B.Fab")
		)
		(fp_line
			(start 0.504 -0.248)
			(end -0.494 -0.248)
			(stroke
				(width 0.15)
				(type solid)
			)
			(layer "B.Fab")
		)
		(fp_line
			(start -0.494 0.25)
			(end 0.504 0.25)
			(stroke
				(width 0.15)
				(type solid)
			)
			(layer "B.Fab")
		)
		(fp_line
			(start -0.494 -0.248)
			(end -0.494 0.25)
			(stroke
				(width 0.15)
				(type solid)
			)
			(layer "B.Fab")
		)
		(fp_text user "Author: Antmicro"
			(at -0.939 -3.399 0)
			(layer "B.Fab")
			(effects
				(font
					(size 0.7 0.7)
					(thickness 0.15)
				)
				(justify left bottom mirror)
			)
		)
		(fp_text user "License: Apache-2.0"
			(at -0.939 -5.799 0)
			(layer "B.Fab")
			(effects
				(font
					(size 0.7 0.7)
					(thickness 0.15)
				)
				(justify left bottom mirror)
			)
		)
		(fp_text user "${REFERENCE}"
			(at -0.939 -4.599 0)
			(layer "B.Fab")
			(effects
				(font
					(size 0.7 0.7)
					(thickness 0.15)
				)
				(justify left bottom mirror)
			)
		)
		(pad "1" smd roundrect
			(at -0.48 0 180)
			(size 0.59 0.64)
			(layers "B.Cu" "B.Mask" "B.Paste")
			(roundrect_rratio 0.25)
			(net 115 "/USB Hub/USBC4_VBUS")
			(pintype "passive")
		)
		(pad "2" smd roundrect
			(at 0.48 0 180)
			(size 0.59 0.64)
			(layers "B.Cu" "B.Mask" "B.Paste")
			(roundrect_rratio 0.25)
			(net 1 "GND")
			(pintype "passive")
		)
	)
	(footprint "antmicro-footprints:R_0402_1005Metric"
		(layer "B.Cu")
		(at 208.726 147 180)
		(descr "Resistor SMD 0402")
		(tags "resistor SMD 0402")
		(property "Reference" "R198"
			(at -3.8 -0.55 0)
			(layer "B.SilkS")
			(effects
				(font
					(size 0.7 0.7)
					(thickness 0.15)
				)
				(justify left bottom mirror)
			)
		)
		(property "Value" "R_0R_0402"
			(at -1.011843 -1.772047 0)
			(layer "B.Fab")
			(effects
				(font
					(size 0.7 0.7)
					(thickness 0.15)
				)
				(justify left bottom mirror)
			)
		)
		(property "Datasheet" "https://industrial.panasonic.com/cdbs/www-data/pdf/RDA0000/AOA0000C301.pdf"
			(at 0 0 0)
			(layer "B.Fab")
			(hide yes)
			(effects
				(font
					(size 1.27 1.27)
					(thickness 0.15)
				)
				(justify mirror)
			)
		)
		(property "Description" "SMD Chip Resistor, Jumper, 0 ohm, 100 mW, 0402 [1005 Metric], Thick Film, General Purpose"
			(at 0 0 0)
			(layer "B.Fab")
			(hide yes)
			(effects
				(font
					(size 1.27 1.27)
					(thickness 0.15)
				)
				(justify mirror)
			)
		)
		(property "MPN" "ERJ2GE0R00X"
			(at 0 0 0)
			(unlocked yes)
			(layer "B.Fab")
			(hide yes)
			(effects
				(font
					(size 1 1)
					(thickness 0.15)
				)
				(justify mirror)
			)
		)
		(property "Manufacturer" "Panasonic"
			(at 0 0 0)
			(unlocked yes)
			(layer "B.Fab")
			(hide yes)
			(effects
				(font
					(size 1 1)
					(thickness 0.15)
				)
				(justify mirror)
			)
		)
		(property "License" "Apache-2.0"
			(at 0 0 0)
			(unlocked yes)
			(layer "B.Fab")
			(hide yes)
			(effects
				(font
					(size 1 1)
					(thickness 0.15)
				)
				(justify mirror)
			)
		)
		(property "Author" "Antmicro"
			(at 0 0 0)
			(unlocked yes)
			(layer "B.Fab")
			(hide yes)
			(effects
				(font
					(size 1 1)
					(thickness 0.15)
				)
				(justify mirror)
			)
		)
		(property "Val" "0R"
			(at 0 0 0)
			(unlocked yes)
			(layer "B.Fab")
			(hide yes)
			(effects
				(font
					(size 1 1)
					(thickness 0.15)
				)
				(justify mirror)
			)
		)
		(property "Tolerance" "~"
			(at 0 0 0)
			(unlocked yes)
			(layer "B.Fab")
			(hide yes)
			(effects
				(font
					(size 1 1)
					(thickness 0.15)
				)
				(justify mirror)
			)
		)
		(property "Current" "1A"
			(at 0 0 0)
			(unlocked yes)
			(layer "B.Fab")
			(hide yes)
			(effects
				(font
					(size 1 1)
					(thickness 0.15)
				)
				(justify mirror)
			)
		)
		(sheetname "/SFP/")
		(sheetfile "sfp.kicad_sch")
		(attr smd)
		(fp_rect
			(start -0.925 0.47)
			(end 0.925 -0.47)
			(stroke
				(width 0.05)
				(type default)
			)
			(fill no)
			(layer "B.CrtYd")
		)
		(fp_rect
			(start -0.5 0.25)
			(end 0.5 -0.25)
			(stroke
				(width 0.15)
				(type solid)
			)
			(fill no)
			(layer "B.Fab")
		)
		(fp_text user "${REFERENCE}"
			(at -0.95 -3.168 0)
			(layer "B.Fab")
			(effects
				(font
					(size 0.7 0.7)
					(thickness 0.15)
				)
				(justify left bottom mirror)
			)
		)
		(fp_text user "License: Apache-2.0"
			(at -0.95 -5.169 0)
			(layer "B.Fab")
			(effects
				(font
					(size 0.7 0.7)
					(thickness 0.15)
				)
				(justify left bottom mirror)
			)
		)
		(fp_text user "Author: Antmicro"
			(at -0.95 -4.169 0)
			(layer "B.Fab")
			(effects
				(font
					(size 0.7 0.7)
					(thickness 0.15)
				)
				(justify left bottom mirror)
			)
		)
		(pad "1" smd roundrect
			(at -0.48 0 180)
			(size 0.59 0.64)
			(layers "B.Cu" "B.Mask" "B.Paste")
			(roundrect_rratio 0.25)
			(net 1 "GND")
			(pintype "passive")
		)
		(pad "2" smd roundrect
			(at 0.48 0 180)
			(size 0.59 0.64)
			(layers "B.Cu" "B.Mask" "B.Paste")
			(roundrect_rratio 0.25)
			(net 1367 "Net-(J12-TX_{DISABLE})")
			(pintype "passive")
		)
	)
)
